# BASEBOARD_FAB2 (Tioga Pass) — schematic netlist excerpt (pin names and nets, part order shuffled) for the footprints in the layout excerpt that follows; sources: Cadence DE-HDL packaged netlist, KiCad conversion of Wiwynn_Tioga_Pass_MB.brd

R1L32  RES  10.0 1% CHIP  pkg 0402  page 155 : A = LED_POSTCODE_0 ; B = LED_POSTCODE_0_R
R9E10  RES  200.0 1% CHIP  pkg 0402  page 187 : A = RST_PCIE_CPU_DEV1_R_N ; B = RST_PCIE_CPU_DEV1_N
C3W1  CAP  1.0UF 6.3V 10% EMPTY  pkg 0402  page 114 : A = A_PCH_XCLK_BIASREF ; B = GND

(kicad_pcb
	(version 20260206)
	(generator "pcbnew")
	(generator_version "10.0")
	(general
		(thickness 1.6)
		(legacy_teardrops no)
	)
	(paper "A4")
	(title_block
		(title "Wiwynn_Tioga_Pass_MB.brd")
		(comment 1 "Tioga Pass / footprints 2561-2563 of 4770")
	)
	(layers
		(0 "F.Cu" signal "TOP")
		(4 "In1.Cu" signal "L2GND")
		(6 "In2.Cu" signal "L3")
		(8 "In3.Cu" signal "L4GND")
		(10 "In4.Cu" signal "L5")
		(12 "In5.Cu" signal "L6GND")
		(14 "In6.Cu" signal "L7VCC")
		(16 "In7.Cu" signal "L8VCC")
		(18 "In8.Cu" signal "L9GND")
		(20 "In9.Cu" signal "L10")
		(22 "In10.Cu" signal "L11GND")
		(24 "In11.Cu" signal "L12")
		(26 "In12.Cu" signal "L13GND")
		(2 "B.Cu" signal "BOTTOM")
		(9 "F.Adhes" user "F.Adhesive")
		(11 "B.Adhes" user "B.Adhesive")
		(13 "F.Paste" user "Package Geometry/Pastemask Top")
		(15 "B.Paste" user "Package Geometry/Pastemask Bottom")
		(5 "F.SilkS" user "Ref Des/Silkscreen Top")
		(7 "B.SilkS" user "Ref Des/Silkscreen Bottom")
		(1 "F.Mask" user "Board Geometry/Soldermask Top")
		(3 "B.Mask" user "Board Geometry/Soldermask Bottom")
		(17 "Dwgs.User" user "User.Drawings")
		(19 "Cmts.User" user "User.Comments")
		(21 "Eco1.User" user "User.Eco1")
		(23 "Eco2.User" user "User.Eco2")
		(25 "Edge.Cuts" user "Board Geometry/Outline")
		(27 "Margin" user)
		(31 "F.CrtYd" user "Package Geometry/Place Bound Top")
		(29 "B.CrtYd" user "Package Geometry/Place Bound Bottom")
		(35 "F.Fab" user "Ref Des/Assembly Top")
		(33 "B.Fab" user "Ref Des/Assembly Bottom")
	)
	(footprint ""
		(layer "B.Cu")
		(at 375.7041 -110.281212)
		(property "Reference" "C3W1"
			(at 0.8382 -0.67818 0)
			(unlocked yes)
			(layer "B.SilkS")
			(effects
				(font
					(size 0.4064 0.254)
					(thickness 0.1524)
				)
				(justify left mirror)
			)
		)
		(property "Value" ""
			(at 0 0 0)
			(layer "B.Fab")
			(effects
				(font
					(size 1.27 1.27)
				)
				(justify mirror)
			)
		)
		(duplicate_pad_numbers_are_jumpers no)
		(fp_poly
			(pts
				(xy -0.3048 -0.1016) (xy -0.3048 0.9906) (xy 0.3048 0.9906) (xy 0.3048 -0.1016)
			)
			(stroke
				(width 0)
				(type default)
			)
			(fill no)
			(layer "B.CrtYd")
		)
		(fp_line
			(start -0.3048 -0.1016)
			(end 0.3048 -0.1016)
			(stroke
				(width 0.1)
				(type default)
			)
			(layer "B.Fab")
		)
		(fp_line
			(start -0.3048 0.9906)
			(end -0.3048 -0.1016)
			(stroke
				(width 0.1)
				(type default)
			)
			(layer "B.Fab")
		)
		(fp_line
			(start 0.3048 -0.1016)
			(end 0.3048 0.9906)
			(stroke
				(width 0.1)
				(type default)
			)
			(layer "B.Fab")
		)
		(fp_line
			(start 0.3048 0.9906)
			(end -0.3048 0.9906)
			(stroke
				(width 0.1)
				(type default)
			)
			(layer "B.Fab")
		)
		(pad "1" smd rect
			(at 0 0 180)
			(size 0.508 0.508)
			(layers "B.Cu" "B.Mask" "B.Paste")
			(net "A_PCH_XCLK_BIASREF")
		)
		(pad "2" smd rect
			(at 0 0.889 180)
			(size 0.508 0.508)
			(layers "B.Cu" "B.Mask" "B.Paste")
			(net "GND")
		)
		(zone
			(layer "B.Cu")
			(hatch none 0.5)
			(connect_pads
				(clearance 0)
			)
			(min_thickness 0.25)
			(keepout
				(tracks allowed)
				(vias not_allowed)
				(pads allowed)
				(copperpour not_allowed)
				(footprints allowed)
			)
			(placement
				(enabled no)
				(sheetname "")
			)
			(fill
				(thermal_gap 0.5)
				(thermal_bridge_width 0.5)
				(island_removal_mode 0)
			)
			(polygon
				(pts
					(xy 375.9581 -110.027212) (xy 375.4501 -110.027212) (xy 375.4501 -109.646212) (xy 375.9581 -109.646212)
				)
			)
		)
		(zone
			(layer "B.Cu")
			(hatch none 0.5)
			(connect_pads
				(clearance 0)
			)
			(min_thickness 0.25)
			(keepout
				(tracks not_allowed)
				(vias allowed)
				(pads allowed)
				(copperpour not_allowed)
				(footprints allowed)
			)
			(placement
				(enabled no)
				(sheetname "")
			)
			(fill
				(thermal_gap 0.5)
				(thermal_bridge_width 0.5)
				(island_removal_mode 0)
			)
			(polygon
				(pts
					(xy 375.9581 -109.646212) (xy 375.4501 -109.646212) (xy 375.4501 -110.027212) (xy 375.9581 -110.027212)
				)
			)
		)
	)
	(footprint ""
		(layer "B.Cu")
		(at 495.2492 -137.7569 180)
		(property "Reference" "R1L32"
			(at 0 0 0)
			(layer "B.SilkS")
			(hide yes)
			(effects
				(font
					(size 1.27 1.27)
				)
				(justify mirror)
			)
		)
		(property "Value" ""
			(at 0 0 0)
			(layer "B.Fab")
			(effects
				(font
					(size 1.27 1.27)
				)
				(justify mirror)
			)
		)
		(duplicate_pad_numbers_are_jumpers no)
		(fp_poly
			(pts
				(xy 0.2794 -0.1016) (xy -0.2794 -0.1016) (xy -0.2794 0.9906) (xy 0.2794 0.9906)
			)
			(stroke
				(width 0)
				(type default)
			)
			(fill no)
			(layer "B.CrtYd")
		)
		(fp_line
			(start 0.2794 0.9906)
			(end -0.2794 0.9906)
			(stroke
				(width 0.1)
				(type default)
			)
			(layer "B.Fab")
		)
		(fp_line
			(start 0.2794 -0.1016)
			(end 0.2794 0.9906)
			(stroke
				(width 0.1)
				(type default)
			)
			(layer "B.Fab")
		)
		(fp_line
			(start -0.2794 0.9906)
			(end -0.2794 -0.1016)
			(stroke
				(width 0.1)
				(type default)
			)
			(layer "B.Fab")
		)
		(fp_line
			(start -0.2794 -0.1016)
			(end 0.2794 -0.1016)
			(stroke
				(width 0.1)
				(type default)
			)
			(layer "B.Fab")
		)
		(pad "1" smd rect
			(at 0 0)
			(size 0.508 0.508)
			(layers "B.Cu" "B.Mask" "B.Paste")
			(net "LED_POSTCODE_0")
		)
		(pad "2" smd rect
			(at 0 0.889)
			(size 0.508 0.508)
			(layers "B.Cu" "B.Mask" "B.Paste")
			(net "LED_POSTCODE_0_R")
		)
		(zone
			(layer "B.Cu")
			(hatch none 0.5)
			(connect_pads
				(clearance 0)
			)
			(min_thickness 0.25)
			(keepout
				(tracks not_allowed)
				(vias allowed)
				(pads allowed)
				(copperpour not_allowed)
				(footprints allowed)
			)
			(placement
				(enabled no)
				(sheetname "")
			)
			(fill
				(thermal_gap 0.5)
				(thermal_bridge_width 0.5)
				(island_removal_mode 0)
			)
			(polygon
				(pts
					(xy 494.9952 -138.3919) (xy 495.5032 -138.3919) (xy 495.5032 -138.0109) (xy 494.9952 -138.0109)
				)
			)
		)
		(zone
			(layer "B.Cu")
			(hatch none 0.5)
			(connect_pads
				(clearance 0)
			)
			(min_thickness 0.25)
			(keepout
				(tracks allowed)
				(vias not_allowed)
				(pads allowed)
				(copperpour not_allowed)
				(footprints allowed)
			)
			(placement
				(enabled no)
				(sheetname "")
			)
			(fill
				(thermal_gap 0.5)
				(thermal_bridge_width 0.5)
				(island_removal_mode 0)
			)
			(polygon
				(pts
					(xy 494.9952 -138.0109) (xy 495.5032 -138.0109) (xy 495.5032 -138.3919) (xy 494.9952 -138.3919)
				)
			)
		)
	)
	(footprint ""
		(layer "B.Cu")
		(at 467.106 -46.6725 180)
		(property "Reference" "R9E10"
			(at 0 0 0)
			(layer "B.SilkS")
			(hide yes)
			(effects
				(font
					(size 1.27 1.27)
				)
				(justify mirror)
			)
		)
		(property "Value" ""
			(at 0 0 0)
			(layer "B.Fab")
			(effects
				(font
					(size 1.27 1.27)
				)
				(justify mirror)
			)
		)
		(duplicate_pad_numbers_are_jumpers no)
		(fp_poly
			(pts
				(xy 0.2794 -0.1016) (xy -0.2794 -0.1016) (xy -0.2794 0.9906) (xy 0.2794 0.9906)
			)
			(stroke
				(width 0)
				(type default)
			)
			(fill no)
			(layer "B.CrtYd")
		)
		(fp_line
			(start 0.2794 0.9906)
			(end -0.2794 0.9906)
			(stroke
				(width 0.1)
				(type default)
			)
			(layer "B.Fab")
		)
		(fp_line
			(start 0.2794 -0.1016)
			(end 0.2794 0.9906)
			(stroke
				(width 0.1)
				(type default)
			)
			(layer "B.Fab")
		)
		(fp_line
			(start -0.2794 0.9906)
			(end -0.2794 -0.1016)
			(stroke
				(width 0.1)
				(type default)
			)
			(layer "B.Fab")
		)
		(fp_line
			(start -0.2794 -0.1016)
			(end 0.2794 -0.1016)
			(stroke
				(width 0.1)
				(type default)
			)
			(layer "B.Fab")
		)
		(pad "1" smd rect
			(at 0 0)
			(size 0.508 0.508)
			(layers "B.Cu" "B.Mask" "B.Paste")
			(net "RST_PCIE_CPU_DEV1_R_N")
		)
		(pad "2" smd rect
			(at 0 0.889)
			(size 0.508 0.508)
			(layers "B.Cu" "B.Mask" "B.Paste")
			(net "RST_PCIE_CPU_DEV1_N")
		)
		(zone
			(layer "B.Cu")
			(hatch none 0.5)
			(connect_pads
				(clearance 0)
			)
			(min_thickness 0.25)
			(keepout
				(tracks not_allowed)
				(vias allowed)
				(pads allowed)
				(copperpour not_allowed)
				(footprints allowed)
			)
			(placement
				(enabled no)
				(sheetname "")
			)
			(fill
				(thermal_gap 0.5)
				(thermal_bridge_width 0.5)
				(island_removal_mode 0)
			)
			(polygon
				(pts
					(xy 466.852 -47.3075) (xy 467.36 -47.3075) (xy 467.36 -46.9265) (xy 466.852 -46.9265)
				)
			)
		)
		(zone
			(layer "B.Cu")
			(hatch none 0.5)
			(connect_pads
				(clearance 0)
			)
			(min_thickness 0.25)
			(keepout
				(tracks allowed)
				(vias not_allowed)
				(pads allowed)
				(copperpour not_allowed)
				(footprints allowed)
			)
			(placement
				(enabled no)
				(sheetname "")
			)
			(fill
				(thermal_gap 0.5)
				(thermal_bridge_width 0.5)
				(island_removal_mode 0)
			)
			(polygon
				(pts
					(xy 466.852 -46.9265) (xy 467.36 -46.9265) (xy 467.36 -47.3075) (xy 466.852 -47.3075)
				)
			)
		)
	)
)
